(kicad_pcb
	(version 20260206)
	(generator "pcbnew")
	(generator_version "10.0")
	(general
		(thickness 1.6)
		(legacy_teardrops no)
	)
	(paper "A4")
	(title_block
		(title "03242023_DA0F0TMBIJ0_F0T_Motherboard_J_brd_V01_OCP.brd")
		(comment 1 "Grand Teton / footprints 5871-5877 of 6105")
	)
	(layers
		(0 "F.Cu" signal "TOP")
		(4 "In1.Cu" signal "GND")
		(6 "In2.Cu" signal "IN1")
		(8 "In3.Cu" signal "GND1")
		(10 "In4.Cu" signal "IN2")
		(12 "In5.Cu" signal "GND2")
		(14 "In6.Cu" signal "IN3")
		(16 "In7.Cu" signal "GND3")
		(18 "In8.Cu" signal "VCC")
		(20 "In9.Cu" signal "VCC1")
		(22 "In10.Cu" signal "GND4")
		(24 "In11.Cu" signal "IN4")
		(26 "In12.Cu" signal "GND5")
		(28 "In13.Cu" signal "IN5")
		(30 "In14.Cu" signal "GND6")
		(32 "In15.Cu" signal "IN6")
		(34 "In16.Cu" signal "GND7")
		(2 "B.Cu" signal "BOTTOM")
		(9 "F.Adhes" user "F.Adhesive")
		(11 "B.Adhes" user "B.Adhesive")
		(13 "F.Paste" user "Package Geometry/Pastemask Top")
		(15 "B.Paste" user "Package Geometry/Pastemask Bottom")
		(5 "F.SilkS" user "Ref Des/Silkscreen Top")
		(7 "B.SilkS" user "Ref Des/Silkscreen Bottom")
		(1 "F.Mask" user "Board Geometry/Soldermask Top")
		(3 "B.Mask" user "Board Geometry/Soldermask Bottom")
		(17 "Dwgs.User" user "User.Drawings")
		(19 "Cmts.User" user "User.Comments")
		(21 "Eco1.User" user "User.Eco1")
		(23 "Eco2.User" user "User.Eco2")
		(25 "Edge.Cuts" user "Board Geometry/Outline")
		(27 "Margin" user)
		(31 "F.CrtYd" user "Package Geometry/Place Bound Top")
		(29 "B.CrtYd" user "Package Geometry/Place Bound Bottom")
		(35 "F.Fab" user "Ref Des/Assembly Top")
		(33 "B.Fab" user "Ref Des/Assembly Bottom")
	)
	(footprint ""
		(layer "B.Cu")
		(at 134.54888 -9.362948 -90)
		(property "Reference" "R3777"
			(at 0 0 90)
			(layer "B.SilkS")
			(hide yes)
			(effects
				(font
					(size 1.27 1.27)
				)
				(justify mirror)
			)
		)
		(property "Value" ""
			(at 0 0 90)
			(layer "B.Fab")
			(effects
				(font
					(size 1.27 1.27)
				)
				(justify mirror)
			)
		)
		(duplicate_pad_numbers_are_jumpers no)
		(fp_line
			(start -0.7874 0.4064)
			(end 0.7874 0.4064)
			(stroke
				(width 0.1524)
				(type default)
			)
			(layer "B.SilkS")
		)
		(fp_line
			(start 0.7874 0.4064)
			(end 0.7874 -0.4064)
			(stroke
				(width 0.1524)
				(type default)
			)
			(layer "B.SilkS")
		)
		(fp_line
			(start -0.7874 -0.4064)
			(end -0.7874 0.4064)
			(stroke
				(width 0.1524)
				(type default)
			)
			(layer "B.SilkS")
		)
		(fp_line
			(start 0.7874 -0.4064)
			(end -0.7874 -0.4064)
			(stroke
				(width 0.1524)
				(type default)
			)
			(layer "B.SilkS")
		)
		(fp_line
			(start -0.67945 0.3048)
			(end -0.120396 0.3048)
			(stroke
				(width 0.1)
				(type default)
			)
			(layer "B.Fab")
		)
		(fp_line
			(start -0.120396 0.3048)
			(end -0.120396 0.2794)
			(stroke
				(width 0.1)
				(type default)
			)
			(layer "B.Fab")
		)
		(fp_line
			(start 0.12065 0.3048)
			(end 0.67945 0.3048)
			(stroke
				(width 0.1)
				(type default)
			)
			(layer "B.Fab")
		)
		(fp_line
			(start 0.67945 0.3048)
			(end 0.67945 -0.305054)
			(stroke
				(width 0.1)
				(type default)
			)
			(layer "B.Fab")
		)
		(fp_line
			(start -0.120396 0.2794)
			(end 0.12065 0.2794)
			(stroke
				(width 0.1)
				(type default)
			)
			(layer "B.Fab")
		)
		(fp_line
			(start 0.12065 0.2794)
			(end 0.12065 0.3048)
			(stroke
				(width 0.1)
				(type default)
			)
			(layer "B.Fab")
		)
		(fp_line
			(start -0.12065 -0.2794)
			(end -0.12065 -0.3048)
			(stroke
				(width 0.1)
				(type default)
			)
			(layer "B.Fab")
		)
		(fp_line
			(start 0.12065 -0.2794)
			(end -0.12065 -0.2794)
			(stroke
				(width 0.1)
				(type default)
			)
			(layer "B.Fab")
		)
		(fp_line
			(start -0.67945 -0.3048)
			(end -0.67945 0.3048)
			(stroke
				(width 0.1)
				(type default)
			)
			(layer "B.Fab")
		)
		(fp_line
			(start -0.12065 -0.3048)
			(end -0.67945 -0.3048)
			(stroke
				(width 0.1)
				(type default)
			)
			(layer "B.Fab")
		)
		(fp_line
			(start 0.12065 -0.305054)
			(end 0.12065 -0.2794)
			(stroke
				(width 0.1)
				(type default)
			)
			(layer "B.Fab")
		)
		(fp_line
			(start 0.67945 -0.305054)
			(end 0.12065 -0.305054)
			(stroke
				(width 0.1)
				(type default)
			)
			(layer "B.Fab")
		)
		(pad "1" smd circle
			(at 0.40005 0 90)
			(size 0 0)
			(layers "B.Cu" "B.Mask" "B.Paste")
			(net "FM_UARTSW_LSB_N")
		)
		(pad "2" smd circle
			(at -0.40005 0 90)
			(size 0 0)
			(layers "B.Cu" "B.Mask" "B.Paste")
			(net "FM_UARTSW_LSB_R")
		)
	)
	(footprint ""
		(layer "B.Cu")
		(at 170.12158 -50.107088 180)
		(property "Reference" "C1922"
			(at 0 0 0)
			(layer "B.SilkS")
			(hide yes)
			(effects
				(font
					(size 1.27 1.27)
				)
				(justify mirror)
			)
		)
		(property "Value" ""
			(at 0 0 0)
			(layer "B.Fab")
			(effects
				(font
					(size 1.27 1.27)
				)
				(justify mirror)
			)
		)
		(duplicate_pad_numbers_are_jumpers no)
		(fp_line
			(start 1.2954 0.5842)
			(end 1.2954 -0.5842)
			(stroke
				(width 0.1524)
				(type default)
			)
			(layer "B.SilkS")
		)
		(fp_line
			(start 1.2954 -0.5842)
			(end -1.2954 -0.5842)
			(stroke
				(width 0.1524)
				(type default)
			)
			(layer "B.SilkS")
		)
		(fp_line
			(start 0 -0.5842)
			(end 0 0.5842)
			(stroke
				(width 0.1524)
				(type default)
			)
			(layer "B.SilkS")
		)
		(fp_line
			(start -1.2954 0.5842)
			(end 1.2954 0.5842)
			(stroke
				(width 0.1524)
				(type default)
			)
			(layer "B.SilkS")
		)
		(fp_line
			(start -1.2954 -0.5842)
			(end -1.2954 0.5842)
			(stroke
				(width 0.1524)
				(type default)
			)
			(layer "B.SilkS")
		)
		(fp_line
			(start 1.1938 0.4064)
			(end 1.1938 -0.4064)
			(stroke
				(width 0.1)
				(type default)
			)
			(layer "B.Fab")
		)
		(fp_line
			(start 1.1938 -0.4064)
			(end 0.8636 -0.4064)
			(stroke
				(width 0.1)
				(type default)
			)
			(layer "B.Fab")
		)
		(fp_line
			(start 0.8636 0.4572)
			(end 0.8636 0.4064)
			(stroke
				(width 0.1)
				(type default)
			)
			(layer "B.Fab")
		)
		(fp_line
			(start 0.8636 0.4064)
			(end 1.1938 0.4064)
			(stroke
				(width 0.1)
				(type default)
			)
			(layer "B.Fab")
		)
		(fp_line
			(start 0.8636 -0.4064)
			(end 0.8636 -0.4572)
			(stroke
				(width 0.1)
				(type default)
			)
			(layer "B.Fab")
		)
		(fp_line
			(start 0.8636 -0.4572)
			(end -0.8636 -0.4572)
			(stroke
				(width 0.1)
				(type default)
			)
			(layer "B.Fab")
		)
		(fp_line
			(start -0.8636 0.4572)
			(end 0.8636 0.4572)
			(stroke
				(width 0.1)
				(type default)
			)
			(layer "B.Fab")
		)
		(fp_line
			(start -0.8636 0.4064)
			(end -0.8636 0.4572)
			(stroke
				(width 0.1)
				(type default)
			)
			(layer "B.Fab")
		)
		(fp_line
			(start -0.8636 -0.4064)
			(end -1.1938 -0.4064)
			(stroke
				(width 0.1)
				(type default)
			)
			(layer "B.Fab")
		)
		(fp_line
			(start -0.8636 -0.4572)
			(end -0.8636 -0.4064)
			(stroke
				(width 0.1)
				(type default)
			)
			(layer "B.Fab")
		)
		(fp_line
			(start -1.1938 0.4064)
			(end -0.8636 0.4064)
			(stroke
				(width 0.1)
				(type default)
			)
			(layer "B.Fab")
		)
		(fp_line
			(start -1.1938 -0.4064)
			(end -1.1938 0.4064)
			(stroke
				(width 0.1)
				(type default)
			)
			(layer "B.Fab")
		)
		(pad "1" smd rect
			(at 0.7366 0 90)
			(size 0.7112 0.8128)
			(layers "B.Cu" "B.Mask" "B.Paste")
			(net "P3V3_M2_0")
		)
		(pad "2" smd rect
			(at -0.7366 0 90)
			(size 0.7112 0.8128)
			(layers "B.Cu" "B.Mask" "B.Paste")
			(net "GND")
		)
	)
	(footprint ""
		(layer "B.Cu")
		(at 118.18112 -244.82044 -90)
		(property "Reference" "C317"
			(at 0 0 90)
			(layer "B.SilkS")
			(hide yes)
			(effects
				(font
					(size 1.27 1.27)
				)
				(justify mirror)
			)
		)
		(property "Value" ""
			(at 0 0 90)
			(layer "B.Fab")
			(effects
				(font
					(size 1.27 1.27)
				)
				(justify mirror)
			)
		)
		(duplicate_pad_numbers_are_jumpers no)
		(fp_line
			(start -1.524 0.762)
			(end 1.524 0.762)
			(stroke
				(width 0.1524)
				(type default)
			)
			(layer "B.SilkS")
		)
		(fp_line
			(start 1.524 0.762)
			(end 1.524 -0.762)
			(stroke
				(width 0.1524)
				(type default)
			)
			(layer "B.SilkS")
		)
		(fp_line
			(start -1.524 -0.762)
			(end -1.524 0.762)
			(stroke
				(width 0.1524)
				(type default)
			)
			(layer "B.SilkS")
		)
		(fp_line
			(start 1.524 -0.762)
			(end -1.524 -0.762)
			(stroke
				(width 0.1524)
				(type default)
			)
			(layer "B.SilkS")
		)
		(fp_line
			(start -1.1049 0.724916)
			(end -1.1049 -0.724916)
			(stroke
				(width 0.1)
				(type default)
			)
			(layer "B.Fab")
		)
		(fp_line
			(start 1.1049 0.724916)
			(end -1.1049 0.724916)
			(stroke
				(width 0.1)
				(type default)
			)
			(layer "B.Fab")
		)
		(fp_line
			(start -1.1049 -0.724916)
			(end 1.1049 -0.724916)
			(stroke
				(width 0.1)
				(type default)
			)
			(layer "B.Fab")
		)
		(fp_line
			(start 1.1049 -0.724916)
			(end 1.1049 0.724916)
			(stroke
				(width 0.1)
				(type default)
			)
			(layer "B.Fab")
		)
		(pad "1" smd rect
			(at 0.889 0 270)
			(size 1.016 1.27)
			(layers "B.Cu" "B.Mask" "B.Paste")
			(net "PVCCIN_CPU1")
		)
		(pad "2" smd rect
			(at -0.889 0 270)
			(size 1.016 1.27)
			(layers "B.Cu" "B.Mask" "B.Paste")
			(net "GND")
		)
	)
	(footprint ""
		(layer "B.Cu")
		(at 72.82688 -11.267948 90)
		(property "Reference" "R3163"
			(at 0 0 90)
			(layer "B.SilkS")
			(hide yes)
			(effects
				(font
					(size 1.27 1.27)
				)
				(justify mirror)
			)
		)
		(property "Value" ""
			(at 0 0 90)
			(layer "B.Fab")
			(effects
				(font
					(size 1.27 1.27)
				)
				(justify mirror)
			)
		)
		(duplicate_pad_numbers_are_jumpers no)
		(fp_line
			(start 0.7874 -0.4064)
			(end -0.7874 -0.4064)
			(stroke
				(width 0.1524)
				(type default)
			)
			(layer "B.SilkS")
		)
		(fp_line
			(start -0.7874 -0.4064)
			(end -0.7874 0.4064)
			(stroke
				(width 0.1524)
				(type default)
			)
			(layer "B.SilkS")
		)
		(fp_line
			(start 0.7874 0.4064)
			(end 0.7874 -0.4064)
			(stroke
				(width 0.1524)
				(type default)
			)
			(layer "B.SilkS")
		)
		(fp_line
			(start -0.7874 0.4064)
			(end 0.7874 0.4064)
			(stroke
				(width 0.1524)
				(type default)
			)
			(layer "B.SilkS")
		)
		(fp_line
			(start 0.67945 -0.305054)
			(end 0.12065 -0.305054)
			(stroke
				(width 0.1)
				(type default)
			)
			(layer "B.Fab")
		)
		(fp_line
			(start 0.12065 -0.305054)
			(end 0.12065 -0.2794)
			(stroke
				(width 0.1)
				(type default)
			)
			(layer "B.Fab")
		)
		(fp_line
			(start -0.12065 -0.3048)
			(end -0.67945 -0.3048)
			(stroke
				(width 0.1)
				(type default)
			)
			(layer "B.Fab")
		)
		(fp_line
			(start -0.67945 -0.3048)
			(end -0.67945 0.3048)
			(stroke
				(width 0.1)
				(type default)
			)
			(layer "B.Fab")
		)
		(fp_line
			(start 0.12065 -0.2794)
			(end -0.12065 -0.2794)
			(stroke
				(width 0.1)
				(type default)
			)
			(layer "B.Fab")
		)
		(fp_line
			(start -0.12065 -0.2794)
			(end -0.12065 -0.3048)
			(stroke
				(width 0.1)
				(type default)
			)
			(layer "B.Fab")
		)
		(fp_line
			(start 0.12065 0.2794)
			(end 0.12065 0.3048)
			(stroke
				(width 0.1)
				(type default)
			)
			(layer "B.Fab")
		)
		(fp_line
			(start -0.120396 0.2794)
			(end 0.12065 0.2794)
			(stroke
				(width 0.1)
				(type default)
			)
			(layer "B.Fab")
		)
		(fp_line
			(start 0.67945 0.3048)
			(end 0.67945 -0.305054)
			(stroke
				(width 0.1)
				(type default)
			)
			(layer "B.Fab")
		)
		(fp_line
			(start 0.12065 0.3048)
			(end 0.67945 0.3048)
			(stroke
				(width 0.1)
				(type default)
			)
			(layer "B.Fab")
		)
		(fp_line
			(start -0.120396 0.3048)
			(end -0.120396 0.2794)
			(stroke
				(width 0.1)
				(type default)
			)
			(layer "B.Fab")
		)
		(fp_line
			(start -0.67945 0.3048)
			(end -0.120396 0.3048)
			(stroke
				(width 0.1)
				(type default)
			)
			(layer "B.Fab")
		)
		(pad "1" smd circle
			(at 0.40005 0 270)
			(size 0 0)
			(layers "B.Cu" "B.Mask" "B.Paste")
			(net "OCP_V3_2_ID0")
		)
		(pad "2" smd circle
			(at -0.40005 0 270)
			(size 0 0)
			(layers "B.Cu" "B.Mask" "B.Paste")
			(net "GND")
		)
	)
	(footprint ""
		(layer "B.Cu")
		(at 36.968938 -125.38456)
		(property "Reference" "R2556"
			(at 0 0 0)
			(layer "B.SilkS")
			(hide yes)
			(effects
				(font
					(size 1.27 1.27)
				)
				(justify mirror)
			)
		)
		(property "Value" ""
			(at 0 0 0)
			(layer "B.Fab")
			(effects
				(font
					(size 1.27 1.27)
				)
				(justify mirror)
			)
		)
		(duplicate_pad_numbers_are_jumpers no)
		(fp_line
			(start -0.7874 -0.4064)
			(end -0.7874 0.4064)
			(stroke
				(width 0.1524)
				(type default)
			)
			(layer "B.SilkS")
		)
		(fp_line
			(start -0.7874 0.4064)
			(end 0.7874 0.4064)
			(stroke
				(width 0.1524)
				(type default)
			)
			(layer "B.SilkS")
		)
		(fp_line
			(start 0.7874 -0.4064)
			(end -0.7874 -0.4064)
			(stroke
				(width 0.1524)
				(type default)
			)
			(layer "B.SilkS")
		)
		(fp_line
			(start 0.7874 0.4064)
			(end 0.7874 -0.4064)
			(stroke
				(width 0.1524)
				(type default)
			)
			(layer "B.SilkS")
		)
		(fp_line
			(start -0.67945 -0.3048)
			(end -0.67945 0.3048)
			(stroke
				(width 0.1)
				(type default)
			)
			(layer "B.Fab")
		)
		(fp_line
			(start -0.67945 0.3048)
			(end -0.120396 0.3048)
			(stroke
				(width 0.1)
				(type default)
			)
			(layer "B.Fab")
		)
		(fp_line
			(start -0.12065 -0.3048)
			(end -0.67945 -0.3048)
			(stroke
				(width 0.1)
				(type default)
			)
			(layer "B.Fab")
		)
		(fp_line
			(start -0.12065 -0.2794)
			(end -0.12065 -0.3048)
			(stroke
				(width 0.1)
				(type default)
			)
			(layer "B.Fab")
		)
		(fp_line
			(start -0.120396 0.2794)
			(end 0.12065 0.2794)
			(stroke
				(width 0.1)
				(type default)
			)
			(layer "B.Fab")
		)
		(fp_line
			(start -0.120396 0.3048)
			(end -0.120396 0.2794)
			(stroke
				(width 0.1)
				(type default)
			)
			(layer "B.Fab")
		)
		(fp_line
			(start 0.12065 -0.305054)
			(end 0.12065 -0.2794)
			(stroke
				(width 0.1)
				(type default)
			)
			(layer "B.Fab")
		)
		(fp_line
			(start 0.12065 -0.2794)
			(end -0.12065 -0.2794)
			(stroke
				(width 0.1)
				(type default)
			)
			(layer "B.Fab")
		)
		(fp_line
			(start 0.12065 0.2794)
			(end 0.12065 0.3048)
			(stroke
				(width 0.1)
				(type default)
			)
			(layer "B.Fab")
		)
		(fp_line
			(start 0.12065 0.3048)
			(end 0.67945 0.3048)
			(stroke
				(width 0.1)
				(type default)
			)
			(layer "B.Fab")
		)
		(fp_line
			(start 0.67945 -0.305054)
			(end 0.12065 -0.305054)
			(stroke
				(width 0.1)
				(type default)
			)
			(layer "B.Fab")
		)
		(fp_line
			(start 0.67945 0.3048)
			(end 0.67945 -0.305054)
			(stroke
				(width 0.1)
				(type default)
			)
			(layer "B.Fab")
		)
		(pad "1" smd circle
			(at 0.40005 0 180)
			(size 0 0)
			(layers "B.Cu" "B.Mask" "B.Paste")
			(net "P3V3_AUX")
		)
		(pad "2" smd circle
			(at -0.40005 0 180)
			(size 0 0)
			(layers "B.Cu" "B.Mask" "B.Paste")
			(net "PWRGD_PVCCINFAON_CPU1_R")
		)
	)
	(footprint ""
		(layer "B.Cu")
		(at 176.555654 -110.975394 -90)
		(property "Reference" "C1898"
			(at 0 0 90)
			(layer "B.SilkS")
			(hide yes)
			(effects
				(font
					(size 1.27 1.27)
				)
				(justify mirror)
			)
		)
		(property "Value" ""
			(at 0 0 90)
			(layer "B.Fab")
			(effects
				(font
					(size 1.27 1.27)
				)
				(justify mirror)
			)
		)
		(duplicate_pad_numbers_are_jumpers no)
		(fp_line
			(start -0.69215 0.2921)
			(end 0.69215 0.2921)
			(stroke
				(width 0.1524)
				(type default)
			)
			(layer "B.SilkS")
		)
		(fp_line
			(start 0.69215 0.2921)
			(end 0.69215 -0.2921)
			(stroke
				(width 0.1524)
				(type default)
			)
			(layer "B.SilkS")
		)
		(fp_line
			(start -0.69215 -0.2921)
			(end -0.69215 0.2921)
			(stroke
				(width 0.1524)
				(type default)
			)
			(layer "B.SilkS")
		)
		(fp_line
			(start 0.69215 -0.2921)
			(end -0.69215 -0.2921)
			(stroke
				(width 0.1524)
				(type default)
			)
			(layer "B.SilkS")
		)
		(fp_line
			(start -0.51435 0.2794)
			(end 0.51435 0.2794)
			(stroke
				(width 0.1)
				(type default)
			)
			(layer "B.Fab")
		)
		(fp_line
			(start 0.51435 0.2794)
			(end 0.51435 -0.2794)
			(stroke
				(width 0.1)
				(type default)
			)
			(layer "B.Fab")
		)
		(fp_line
			(start -0.51435 -0.2794)
			(end -0.51435 0.2794)
			(stroke
				(width 0.1)
				(type default)
			)
			(layer "B.Fab")
		)
		(fp_line
			(start 0.51435 -0.2794)
			(end -0.51435 -0.2794)
			(stroke
				(width 0.1)
				(type default)
			)
			(layer "B.Fab")
		)
		(pad "1" smd circle
			(at 0.40005 0 90)
			(size 0 0)
			(layers "B.Cu" "B.Mask" "B.Paste")
			(net "P3V3_AUX_FPGA_VCCIO5")
		)
		(pad "2" smd circle
			(at -0.40005 0 90)
			(size 0 0)
			(layers "B.Cu" "B.Mask" "B.Paste")
			(net "GND")
		)
		(zone
			(layer "B.Cu")
			(hatch none 0.5)
			(connect_pads
				(clearance 0)
			)
			(min_thickness 0.25)
			(keepout
				(tracks not_allowed)
				(vias allowed)
				(pads allowed)
				(copperpour not_allowed)
				(footprints allowed)
			)
			(placement
				(enabled no)
				(sheetname "")
			)
			(fill
				(thermal_gap 0.5)
				(thermal_bridge_width 0.5)
				(island_removal_mode 0)
			)
			(polygon
				(pts
					(xy 176.468024 -110.784894) (xy 176.409858 -110.876334) (xy 176.409858 -111.075724) (xy 176.468024 -111.165894)
					(xy 176.643284 -111.165894) (xy 176.701704 -111.075724) (xy 176.701704 -110.876334) (xy 176.643538 -110.784894)
				)
			)
		)
	)
	(footprint ""
		(layer "B.Cu")
		(at 364.342934 -259.531866 90)
		(property "Reference" "C497"
			(at 0 0 90)
			(layer "B.SilkS")
			(hide yes)
			(effects
				(font
					(size 1.27 1.27)
				)
				(justify mirror)
			)
		)
		(property "Value" ""
			(at 0 0 90)
			(layer "B.Fab")
			(effects
				(font
					(size 1.27 1.27)
				)
				(justify mirror)
			)
		)
		(duplicate_pad_numbers_are_jumpers no)
		(fp_line
			(start 1.524 -0.762)
			(end -1.524 -0.762)
			(stroke
				(width 0.1524)
				(type default)
			)
			(layer "B.SilkS")
		)
		(fp_line
			(start -1.524 -0.762)
			(end -1.524 0.762)
			(stroke
				(width 0.1524)
				(type default)
			)
			(layer "B.SilkS")
		)
		(fp_line
			(start 1.524 0.762)
			(end 1.524 -0.762)
			(stroke
				(width 0.1524)
				(type default)
			)
			(layer "B.SilkS")
		)
		(fp_line
			(start -1.524 0.762)
			(end 1.524 0.762)
			(stroke
				(width 0.1524)
				(type default)
			)
			(layer "B.SilkS")
		)
		(fp_line
			(start 1.1049 -0.724916)
			(end 1.1049 0.724916)
			(stroke
				(width 0.1)
				(type default)
			)
			(layer "B.Fab")
		)
		(fp_line
			(start -1.1049 -0.724916)
			(end 1.1049 -0.724916)
			(stroke
				(width 0.1)
				(type default)
			)
			(layer "B.Fab")
		)
		(fp_line
			(start 1.1049 0.724916)
			(end -1.1049 0.724916)
			(stroke
				(width 0.1)
				(type default)
			)
			(layer "B.Fab")
		)
		(fp_line
			(start -1.1049 0.724916)
			(end -1.1049 -0.724916)
			(stroke
				(width 0.1)
				(type default)
			)
			(layer "B.Fab")
		)
		(pad "1" smd rect
			(at 0.889 0 90)
			(size 1.016 1.27)
			(layers "B.Cu" "B.Mask" "B.Paste")
			(net "PVCCFA_EHV_FIVRA_CPU0")
		)
		(pad "2" smd rect
			(at -0.889 0 90)
			(size 1.016 1.27)
			(layers "B.Cu" "B.Mask" "B.Paste")
			(net "GND")
		)
	)
)
